(kicad_pcb
	(version 20260206)
	(generator "pcbnew")
	(generator_version "10.0")
	(general
		(thickness 1.6)
		(legacy_teardrops no)
	)
	(paper "A4")
	(title_block
		(title "Wiwynn_Tioga_Pass_MB.brd")
		(comment 1 "Tioga Pass / footprints 4321-4327 of 4770")
	)
	(layers
		(0 "F.Cu" signal "TOP")
		(4 "In1.Cu" signal "L2GND")
		(6 "In2.Cu" signal "L3")
		(8 "In3.Cu" signal "L4GND")
		(10 "In4.Cu" signal "L5")
		(12 "In5.Cu" signal "L6GND")
		(14 "In6.Cu" signal "L7VCC")
		(16 "In7.Cu" signal "L8VCC")
		(18 "In8.Cu" signal "L9GND")
		(20 "In9.Cu" signal "L10")
		(22 "In10.Cu" signal "L11GND")
		(24 "In11.Cu" signal "L12")
		(26 "In12.Cu" signal "L13GND")
		(2 "B.Cu" signal "BOTTOM")
		(9 "F.Adhes" user "F.Adhesive")
		(11 "B.Adhes" user "B.Adhesive")
		(13 "F.Paste" user "Package Geometry/Pastemask Top")
		(15 "B.Paste" user "Package Geometry/Pastemask Bottom")
		(5 "F.SilkS" user "Ref Des/Silkscreen Top")
		(7 "B.SilkS" user "Ref Des/Silkscreen Bottom")
		(1 "F.Mask" user "Board Geometry/Soldermask Top")
		(3 "B.Mask" user "Board Geometry/Soldermask Bottom")
		(17 "Dwgs.User" user "User.Drawings")
		(19 "Cmts.User" user "User.Comments")
		(21 "Eco1.User" user "User.Eco1")
		(23 "Eco2.User" user "User.Eco2")
		(25 "Edge.Cuts" user "Board Geometry/Outline")
		(27 "Margin" user)
		(31 "F.CrtYd" user "Package Geometry/Place Bound Top")
		(29 "B.CrtYd" user "Package Geometry/Place Bound Bottom")
		(35 "F.Fab" user "Ref Des/Assembly Top")
		(33 "B.Fab" user "Ref Des/Assembly Bottom")
	)
	(footprint ""
		(layer "B.Cu")
		(at 392.117326 -113.903252 90)
		(property "Reference" "C2M20"
			(at 0 0 90)
			(layer "B.SilkS")
			(hide yes)
			(effects
				(font
					(size 1.27 1.27)
				)
				(justify mirror)
			)
		)
		(property "Value" ""
			(at 0 0 90)
			(layer "B.Fab")
			(effects
				(font
					(size 1.27 1.27)
				)
				(justify mirror)
			)
		)
		(duplicate_pad_numbers_are_jumpers no)
		(fp_poly
			(pts
				(xy -0.3048 -0.1016) (xy -0.3048 0.9906) (xy 0.3048 0.9906) (xy 0.3048 -0.1016)
			)
			(stroke
				(width 0)
				(type default)
			)
			(fill no)
			(layer "B.CrtYd")
		)
		(fp_line
			(start 0.3048 -0.1016)
			(end 0.3048 0.9906)
			(stroke
				(width 0.1)
				(type default)
			)
			(layer "B.Fab")
		)
		(fp_line
			(start -0.3048 -0.1016)
			(end 0.3048 -0.1016)
			(stroke
				(width 0.1)
				(type default)
			)
			(layer "B.Fab")
		)
		(fp_line
			(start 0.3048 0.9906)
			(end -0.3048 0.9906)
			(stroke
				(width 0.1)
				(type default)
			)
			(layer "B.Fab")
		)
		(fp_line
			(start -0.3048 0.9906)
			(end -0.3048 -0.1016)
			(stroke
				(width 0.1)
				(type default)
			)
			(layer "B.Fab")
		)
		(pad "1" smd rect
			(at 0 0 270)
			(size 0.508 0.508)
			(layers "B.Cu" "B.Mask" "B.Paste")
			(net "P1V05_PCH_STBY")
		)
		(pad "2" smd rect
			(at 0 0.889 270)
			(size 0.508 0.508)
			(layers "B.Cu" "B.Mask" "B.Paste")
			(net "GND")
		)
		(zone
			(layer "B.Cu")
			(hatch none 0.5)
			(connect_pads
				(clearance 0)
			)
			(min_thickness 0.25)
			(keepout
				(tracks allowed)
				(vias not_allowed)
				(pads allowed)
				(copperpour not_allowed)
				(footprints allowed)
			)
			(placement
				(enabled no)
				(sheetname "")
			)
			(fill
				(thermal_gap 0.5)
				(thermal_bridge_width 0.5)
				(island_removal_mode 0)
			)
			(polygon
				(pts
					(xy 392.371326 -114.157252) (xy 392.371326 -113.649252) (xy 392.752326 -113.649252) (xy 392.752326 -114.157252)
				)
			)
		)
		(zone
			(layer "B.Cu")
			(hatch none 0.5)
			(connect_pads
				(clearance 0)
			)
			(min_thickness 0.25)
			(keepout
				(tracks not_allowed)
				(vias allowed)
				(pads allowed)
				(copperpour not_allowed)
				(footprints allowed)
			)
			(placement
				(enabled no)
				(sheetname "")
			)
			(fill
				(thermal_gap 0.5)
				(thermal_bridge_width 0.5)
				(island_removal_mode 0)
			)
			(polygon
				(pts
					(xy 392.752326 -114.157252) (xy 392.752326 -113.649252) (xy 392.371326 -113.649252) (xy 392.371326 -114.157252)
				)
			)
		)
	)
	(footprint ""
		(layer "B.Cu")
		(at 255.38938 -157.57652 90)
		(property "Reference" "SH5L1"
			(at 0 0 90)
			(layer "B.SilkS")
			(hide yes)
			(effects
				(font
					(size 1.27 1.27)
				)
				(justify mirror)
			)
		)
		(property "Value" ""
			(at 0 0 90)
			(layer "B.Fab")
			(effects
				(font
					(size 1.27 1.27)
				)
				(justify mirror)
			)
		)
		(duplicate_pad_numbers_are_jumpers no)
		(fp_poly
			(pts
				(xy 0.1651 -0.0508) (xy 0.1651 0.5842) (xy -0.1651 0.5842) (xy -0.1651 -0.0508)
			)
			(stroke
				(width 0)
				(type default)
			)
			(fill no)
			(layer "B.CrtYd")
		)
		(fp_line
			(start 0.1651 -0.0508)
			(end -0.1651 -0.0508)
			(stroke
				(width 0.1)
				(type default)
			)
			(layer "B.Fab")
		)
		(fp_line
			(start -0.1651 -0.0508)
			(end -0.1651 0.5842)
			(stroke
				(width 0.1)
				(type default)
			)
			(layer "B.Fab")
		)
		(fp_line
			(start 0.1651 0.5842)
			(end 0.1651 -0.0508)
			(stroke
				(width 0.1)
				(type default)
			)
			(layer "B.Fab")
		)
		(fp_line
			(start -0.1651 0.5842)
			(end 0.1651 0.5842)
			(stroke
				(width 0.1)
				(type default)
			)
			(layer "B.Fab")
		)
		(pad "1" smd custom
			(at 0 0 90)
			(size 0.0762 0.0762)
			(layers "B.Cu" "B.Mask" "B.Paste")
			(net "VR_PVTT_DEF_SNS")
			(options
				(clearance outline)
				(anchor circle)
			)
			(primitives
				(gr_poly
					(pts
						(arc
							(start -0.1524 0.10795)
							(mid -0.098518 0.130268)
							(end -0.0762 0.18415)
						)
						(xy -0.0762 0.22225) (xy 0.0762 0.22225)
						(arc
							(start 0.0762 0.18415)
							(mid 0.098518 0.130268)
							(end 0.1524 0.10795)
						)
						(xy 0.1524 -0.22225) (xy -0.1524 -0.22225)
					)
					(width 0)
					(fill yes)
				)
			)
		)
		(pad "2" smd custom
			(at 0 0.5334 270)
			(size 0.0762 0.0762)
			(layers "B.Cu" "B.Mask" "B.Paste")
			(net "PVTT_DEF")
			(options
				(clearance outline)
				(anchor circle)
			)
			(primitives
				(gr_poly
					(pts
						(arc
							(start -0.1524 0.10795)
							(mid -0.098518 0.130268)
							(end -0.0762 0.18415)
						)
						(xy -0.0762 0.22225) (xy 0.0762 0.22225)
						(arc
							(start 0.0762 0.18415)
							(mid 0.098518 0.130268)
							(end 0.1524 0.10795)
						)
						(xy 0.1524 -0.22225) (xy -0.1524 -0.22225)
					)
					(width 0)
					(fill yes)
				)
			)
		)
	)
	(footprint ""
		(layer "B.Cu")
		(at 408.1526 -153.5938 90)
		(property "Reference" "C2L7"
			(at 0 0 90)
			(layer "B.SilkS")
			(hide yes)
			(effects
				(font
					(size 1.27 1.27)
				)
				(justify mirror)
			)
		)
		(property "Value" ""
			(at 0 0 90)
			(layer "B.Fab")
			(effects
				(font
					(size 1.27 1.27)
				)
				(justify mirror)
			)
		)
		(duplicate_pad_numbers_are_jumpers no)
		(fp_poly
			(pts
				(xy -0.3048 -0.1016) (xy -0.3048 0.9906) (xy 0.3048 0.9906) (xy 0.3048 -0.1016)
			)
			(stroke
				(width 0)
				(type default)
			)
			(fill no)
			(layer "B.CrtYd")
		)
		(fp_line
			(start 0.3048 -0.1016)
			(end 0.3048 0.9906)
			(stroke
				(width 0.1)
				(type default)
			)
			(layer "B.Fab")
		)
		(fp_line
			(start -0.3048 -0.1016)
			(end 0.3048 -0.1016)
			(stroke
				(width 0.1)
				(type default)
			)
			(layer "B.Fab")
		)
		(fp_line
			(start 0.3048 0.9906)
			(end -0.3048 0.9906)
			(stroke
				(width 0.1)
				(type default)
			)
			(layer "B.Fab")
		)
		(fp_line
			(start -0.3048 0.9906)
			(end -0.3048 -0.1016)
			(stroke
				(width 0.1)
				(type default)
			)
			(layer "B.Fab")
		)
		(pad "1" smd rect
			(at 0 0 270)
			(size 0.508 0.508)
			(layers "B.Cu" "B.Mask" "B.Paste")
			(net "SATA6G_PCH_PCIE_UP_SATA_RXP<7>")
		)
		(pad "2" smd rect
			(at 0 0.889 270)
			(size 0.508 0.508)
			(layers "B.Cu" "B.Mask" "B.Paste")
			(net "SATA6G_P7_RX_C_DP")
		)
		(zone
			(layer "B.Cu")
			(hatch none 0.5)
			(connect_pads
				(clearance 0)
			)
			(min_thickness 0.25)
			(keepout
				(tracks allowed)
				(vias not_allowed)
				(pads allowed)
				(copperpour not_allowed)
				(footprints allowed)
			)
			(placement
				(enabled no)
				(sheetname "")
			)
			(fill
				(thermal_gap 0.5)
				(thermal_bridge_width 0.5)
				(island_removal_mode 0)
			)
			(polygon
				(pts
					(xy 408.4066 -153.8478) (xy 408.4066 -153.3398) (xy 408.7876 -153.3398) (xy 408.7876 -153.8478)
				)
			)
		)
		(zone
			(layer "B.Cu")
			(hatch none 0.5)
			(connect_pads
				(clearance 0)
			)
			(min_thickness 0.25)
			(keepout
				(tracks not_allowed)
				(vias allowed)
				(pads allowed)
				(copperpour not_allowed)
				(footprints allowed)
			)
			(placement
				(enabled no)
				(sheetname "")
			)
			(fill
				(thermal_gap 0.5)
				(thermal_bridge_width 0.5)
				(island_removal_mode 0)
			)
			(polygon
				(pts
					(xy 408.7876 -153.8478) (xy 408.7876 -153.3398) (xy 408.4066 -153.3398) (xy 408.4066 -153.8478)
				)
			)
		)
	)
	(footprint ""
		(layer "B.Cu")
		(at 348.052136 -141.085062 -90)
		(property "Reference" "C7W13"
			(at 0 0 90)
			(layer "B.SilkS")
			(hide yes)
			(effects
				(font
					(size 1.27 1.27)
				)
				(justify mirror)
			)
		)
		(property "Value" "*"
			(at 0.0762 -6.2357 270)
			(unlocked yes)
			(layer "B.Fab")
			(hide yes)
			(effects
				(font
					(size 1.27 1.016)
					(thickness 0.1524)
				)
				(justify mirror)
			)
		)
		(property "Device Type" "SC22U16V5MX-4-GP_SMD-BCG5-SC22A"
			(at 0.0762 -8.2677 270)
			(unlocked yes)
			(layer "B.Fab")
			(hide yes)
			(effects
				(font
					(size 1.27 1.016)
					(thickness 0.1524)
				)
				(justify mirror)
			)
		)
		(duplicate_pad_numbers_are_jumpers no)
		(fp_line
			(start -0.635 0)
			(end 0.635 0)
			(stroke
				(width 0.508)
				(type default)
			)
			(layer "B.SilkS")
		)
		(fp_rect
			(start 0.9652 1.778)
			(end -0.9652 -1.778)
			(stroke
				(width 0)
				(type default)
			)
			(fill no)
			(layer "B.CrtYd")
		)
		(fp_poly
			(pts
				(xy 0.9652 -1.778) (xy -0.9652 -1.778) (xy -0.9652 1.778) (xy 0.9652 1.778)
			)
			(stroke
				(width 0)
				(type default)
			)
			(fill no)
			(layer "B.Fab")
		)
		(pad "1" smd rect
			(at 0 -0.9652 90)
			(size 1.397 1.143)
			(layers "B.Cu" "B.Mask" "B.Paste")
			(net "VR_FET_SW_P12V_STBY_PVDDQ_DEF")
		)
		(pad "2" smd rect
			(at 0 0.9652 90)
			(size 1.397 1.143)
			(layers "B.Cu" "B.Mask" "B.Paste")
			(net "GND")
		)
	)
	(footprint ""
		(layer "B.Cu")
		(at 369.945158 -77.896212 -90)
		(property "Reference" "C3P44"
			(at 0 0 90)
			(layer "B.SilkS")
			(hide yes)
			(effects
				(font
					(size 1.27 1.27)
				)
				(justify mirror)
			)
		)
		(property "Value" ""
			(at 0 0 90)
			(layer "B.Fab")
			(effects
				(font
					(size 1.27 1.27)
				)
				(justify mirror)
			)
		)
		(duplicate_pad_numbers_are_jumpers no)
		(fp_rect
			(start 0.2794 0.9144)
			(end -0.2794 -0.1143)
			(stroke
				(width 0)
				(type default)
			)
			(fill no)
			(layer "B.CrtYd")
		)
		(fp_line
			(start -0.2794 0.9144)
			(end 0.2794 0.9144)
			(stroke
				(width 0.1)
				(type default)
			)
			(layer "B.Fab")
		)
		(fp_line
			(start 0.2794 0.9144)
			(end 0.2794 -0.1143)
			(stroke
				(width 0.1)
				(type default)
			)
			(layer "B.Fab")
		)
		(fp_line
			(start -0.2794 -0.1143)
			(end -0.2794 0.9144)
			(stroke
				(width 0.1)
				(type default)
			)
			(layer "B.Fab")
		)
		(fp_line
			(start 0.2794 -0.1143)
			(end -0.2794 -0.1143)
			(stroke
				(width 0.1)
				(type default)
			)
			(layer "B.Fab")
		)
		(pad "1" smd custom
			(at 0 0 180)
			(size 0.10414 0.10414)
			(layers "B.Cu" "B.Mask" "B.Paste")
			(net "P3V3_STBY")
			(options
				(clearance outline)
				(anchor circle)
			)
			(primitives
				(gr_poly
					(pts
						(xy -0.20828 -0.08636) (xy -0.20828 0.08636) (xy -0.08636 0.20828) (xy 0.086614 0.20828) (xy 0.20828 0.086614)
						(xy 0.20828 -0.08636) (xy 0.08636 -0.20828) (xy -0.08636 -0.20828)
					)
					(width 0)
					(fill yes)
				)
			)
		)
		(pad "2" smd custom
			(at 0 0.8001 180)
			(size 0.10414 0.10414)
			(layers "B.Cu" "B.Mask" "B.Paste")
			(net "GND")
			(options
				(clearance outline)
				(anchor circle)
			)
			(primitives
				(gr_poly
					(pts
						(xy -0.20828 -0.08636) (xy -0.20828 0.08636) (xy -0.08636 0.20828) (xy 0.086614 0.20828) (xy 0.20828 0.086614)
						(xy 0.20828 -0.08636) (xy 0.08636 -0.20828) (xy -0.08636 -0.20828)
					)
					(width 0)
					(fill yes)
				)
			)
		)
		(zone
			(layer "B.Cu")
			(hatch none 0.5)
			(connect_pads
				(clearance 0)
			)
			(min_thickness 0.25)
			(keepout
				(tracks allowed)
				(vias not_allowed)
				(pads allowed)
				(copperpour not_allowed)
				(footprints allowed)
			)
			(placement
				(enabled no)
				(sheetname "")
			)
			(fill
				(thermal_gap 0.5)
				(thermal_bridge_width 0.5)
				(island_removal_mode 0)
			)
			(polygon
				(pts
					(xy 369.735608 -77.808582) (xy 369.354608 -77.808582) (xy 369.354608 -77.983842) (xy 369.735608 -77.984096)
				)
			)
		)
		(zone
			(layer "B.Cu")
			(hatch none 0.5)
			(connect_pads
				(clearance 0)
			)
			(min_thickness 0.25)
			(keepout
				(tracks not_allowed)
				(vias allowed)
				(pads allowed)
				(copperpour not_allowed)
				(footprints allowed)
			)
			(placement
				(enabled no)
				(sheetname "")
			)
			(fill
				(thermal_gap 0.5)
				(thermal_bridge_width 0.5)
				(island_removal_mode 0)
			)
			(polygon
				(pts
					(xy 369.735608 -77.808582) (xy 369.354608 -77.808582) (xy 369.354608 -77.983842) (xy 369.735608 -77.984096)
				)
			)
		)
	)
	(footprint ""
		(layer "B.Cu")
		(at 385.33705 -111.85525 180)
		(property "Reference" "C3N1"
			(at 0 0 0)
			(layer "B.SilkS")
			(hide yes)
			(effects
				(font
					(size 1.27 1.27)
				)
				(justify mirror)
			)
		)
		(property "Value" ""
			(at 0 0 0)
			(layer "B.Fab")
			(effects
				(font
					(size 1.27 1.27)
				)
				(justify mirror)
			)
		)
		(duplicate_pad_numbers_are_jumpers no)
		(fp_rect
			(start 0.2794 0.9144)
			(end -0.2794 -0.1143)
			(stroke
				(width 0)
				(type default)
			)
			(fill no)
			(layer "B.CrtYd")
		)
		(fp_line
			(start 0.2794 0.9144)
			(end 0.2794 -0.1143)
			(stroke
				(width 0.1)
				(type default)
			)
			(layer "B.Fab")
		)
		(fp_line
			(start 0.2794 -0.1143)
			(end -0.2794 -0.1143)
			(stroke
				(width 0.1)
				(type default)
			)
			(layer "B.Fab")
		)
		(fp_line
			(start -0.2794 0.9144)
			(end 0.2794 0.9144)
			(stroke
				(width 0.1)
				(type default)
			)
			(layer "B.Fab")
		)
		(fp_line
			(start -0.2794 -0.1143)
			(end -0.2794 0.9144)
			(stroke
				(width 0.1)
				(type default)
			)
			(layer "B.Fab")
		)
		(pad "1" smd custom
			(at 0 0 90)
			(size 0.10414 0.10414)
			(layers "B.Cu" "B.Mask" "B.Paste")
			(net "PVNN_PCH_STBY")
			(options
				(clearance outline)
				(anchor circle)
			)
			(primitives
				(gr_poly
					(pts
						(xy -0.20828 -0.08636) (xy -0.20828 0.08636) (xy -0.08636 0.20828) (xy 0.086614 0.20828) (xy 0.20828 0.086614)
						(xy 0.20828 -0.08636) (xy 0.08636 -0.20828) (xy -0.08636 -0.20828)
					)
					(width 0)
					(fill yes)
				)
			)
		)
		(pad "2" smd custom
			(at 0 0.8001 90)
			(size 0.10414 0.10414)
			(layers "B.Cu" "B.Mask" "B.Paste")
			(net "GND")
			(options
				(clearance outline)
				(anchor circle)
			)
			(primitives
				(gr_poly
					(pts
						(xy -0.20828 -0.08636) (xy -0.20828 0.08636) (xy -0.08636 0.20828) (xy 0.086614 0.20828) (xy 0.20828 0.086614)
						(xy 0.20828 -0.08636) (xy 0.08636 -0.20828) (xy -0.08636 -0.20828)
					)
					(width 0)
					(fill yes)
				)
			)
		)
		(zone
			(layer "B.Cu")
			(hatch none 0.5)
			(connect_pads
				(clearance 0)
			)
			(min_thickness 0.25)
			(keepout
				(tracks allowed)
				(vias not_allowed)
				(pads allowed)
				(copperpour not_allowed)
				(footprints allowed)
			)
			(placement
				(enabled no)
				(sheetname "")
			)
			(fill
				(thermal_gap 0.5)
				(thermal_bridge_width 0.5)
				(island_removal_mode 0)
			)
			(polygon
				(pts
					(xy 385.24942 -112.0648) (xy 385.24942 -112.4458) (xy 385.42468 -112.4458) (xy 385.424934 -112.0648)
				)
			)
		)
		(zone
			(layer "B.Cu")
			(hatch none 0.5)
			(connect_pads
				(clearance 0)
			)
			(min_thickness 0.25)
			(keepout
				(tracks not_allowed)
				(vias allowed)
				(pads allowed)
				(copperpour not_allowed)
				(footprints allowed)
			)
			(placement
				(enabled no)
				(sheetname "")
			)
			(fill
				(thermal_gap 0.5)
				(thermal_bridge_width 0.5)
				(island_removal_mode 0)
			)
			(polygon
				(pts
					(xy 385.24942 -112.0648) (xy 385.24942 -112.4458) (xy 385.42468 -112.4458) (xy 385.424934 -112.0648)
				)
			)
		)
	)
	(footprint ""
		(layer "B.Cu")
		(at 370.745512 -72.294242)
		(property "Reference" "C2R2"
			(at 0 0 0)
			(layer "B.SilkS")
			(hide yes)
			(effects
				(font
					(size 1.27 1.27)
				)
				(justify mirror)
			)
		)
		(property "Value" ""
			(at 0 0 0)
			(layer "B.Fab")
			(effects
				(font
					(size 1.27 1.27)
				)
				(justify mirror)
			)
		)
		(duplicate_pad_numbers_are_jumpers no)
		(fp_rect
			(start 0.2794 0.9144)
			(end -0.2794 -0.1143)
			(stroke
				(width 0)
				(type default)
			)
			(fill no)
			(layer "B.CrtYd")
		)
		(fp_line
			(start -0.2794 -0.1143)
			(end -0.2794 0.9144)
			(stroke
				(width 0.1)
				(type default)
			)
			(layer "B.Fab")
		)
		(fp_line
			(start -0.2794 0.9144)
			(end 0.2794 0.9144)
			(stroke
				(width 0.1)
				(type default)
			)
			(layer "B.Fab")
		)
		(fp_line
			(start 0.2794 -0.1143)
			(end -0.2794 -0.1143)
			(stroke
				(width 0.1)
				(type default)
			)
			(layer "B.Fab")
		)
		(fp_line
			(start 0.2794 0.9144)
			(end 0.2794 -0.1143)
			(stroke
				(width 0.1)
				(type default)
			)
			(layer "B.Fab")
		)
		(pad "1" smd custom
			(at 0 0 270)
			(size 0.10414 0.10414)
			(layers "B.Cu" "B.Mask" "B.Paste")
			(net "P3V3_STBY")
			(options
				(clearance outline)
				(anchor circle)
			)
			(primitives
				(gr_poly
					(pts
						(xy -0.20828 -0.08636) (xy -0.20828 0.08636) (xy -0.08636 0.20828) (xy 0.086614 0.20828) (xy 0.20828 0.086614)
						(xy 0.20828 -0.08636) (xy 0.08636 -0.20828) (xy -0.08636 -0.20828)
					)
					(width 0)
					(fill yes)
				)
			)
		)
		(pad "2" smd custom
			(at 0 0.8001 270)
			(size 0.10414 0.10414)
			(layers "B.Cu" "B.Mask" "B.Paste")
			(net "GND")
			(options
				(clearance outline)
				(anchor circle)
			)
			(primitives
				(gr_poly
					(pts
						(xy -0.20828 -0.08636) (xy -0.20828 0.08636) (xy -0.08636 0.20828) (xy 0.086614 0.20828) (xy 0.20828 0.086614)
						(xy 0.20828 -0.08636) (xy 0.08636 -0.20828) (xy -0.08636 -0.20828)
					)
					(width 0)
					(fill yes)
				)
			)
		)
		(zone
			(layer "B.Cu")
			(hatch none 0.5)
			(connect_pads
				(clearance 0)
			)
			(min_thickness 0.25)
			(keepout
				(tracks not_allowed)
				(vias allowed)
				(pads allowed)
				(copperpour not_allowed)
				(footprints allowed)
			)
			(placement
				(enabled no)
				(sheetname "")
			)
			(fill
				(thermal_gap 0.5)
				(thermal_bridge_width 0.5)
				(island_removal_mode 0)
			)
			(polygon
				(pts
					(xy 370.833142 -72.084692) (xy 370.833142 -71.703692) (xy 370.657882 -71.703692) (xy 370.657628 -72.084692)
				)
			)
		)
		(zone
			(layer "B.Cu")
			(hatch none 0.5)
			(connect_pads
				(clearance 0)
			)
			(min_thickness 0.25)
			(keepout
				(tracks allowed)
				(vias not_allowed)
				(pads allowed)
				(copperpour not_allowed)
				(footprints allowed)
			)
			(placement
				(enabled no)
				(sheetname "")
			)
			(fill
				(thermal_gap 0.5)
				(thermal_bridge_width 0.5)
				(island_removal_mode 0)
			)
			(polygon
				(pts
					(xy 370.833142 -72.084692) (xy 370.833142 -71.703692) (xy 370.657882 -71.703692) (xy 370.657628 -72.084692)
				)
			)
		)
	)
)
